(kicad_pcb
	(version 20260206)
	(generator "pcbnew")
	(generator_version "10.0")
	(general
		(thickness 1.6)
		(legacy_teardrops no)
	)
	(paper "A4")
	(title_block
		(title "01162023_DA0F0TEBIF0_F0T_Expander_BD_F_brd_V02_OCP.brd")
		(comment 1 "Grand Teton / footprints 211-216 of 9728")
	)
	(layers
		(0 "F.Cu" signal "TOP")
		(4 "In1.Cu" signal "GND")
		(6 "In2.Cu" signal "VCC")
		(8 "In3.Cu" signal "VCC1")
		(10 "In4.Cu" signal "GND1")
		(12 "In5.Cu" signal "IN1")
		(14 "In6.Cu" signal "GND2")
		(16 "In7.Cu" signal "IN2")
		(18 "In8.Cu" signal "GND3")
		(20 "In9.Cu" signal "IN3")
		(22 "In10.Cu" signal "GND4")
		(24 "In11.Cu" signal "IN4")
		(26 "In12.Cu" signal "GND5")
		(28 "In13.Cu" signal "IN5")
		(30 "In14.Cu" signal "GND6")
		(32 "In15.Cu" signal "IN6")
		(34 "In16.Cu" signal "GND7")
		(2 "B.Cu" signal "BOTTOM")
		(9 "F.Adhes" user "F.Adhesive")
		(11 "B.Adhes" user "B.Adhesive")
		(13 "F.Paste" user "Package Geometry/Pastemask Top")
		(15 "B.Paste" user "Package Geometry/Pastemask Bottom")
		(5 "F.SilkS" user "Ref Des/Silkscreen Top")
		(7 "B.SilkS" user "Ref Des/Silkscreen Bottom")
		(1 "F.Mask" user "Board Geometry/Soldermask Top")
		(3 "B.Mask" user "Board Geometry/Soldermask Bottom")
		(17 "Dwgs.User" user "User.Drawings")
		(19 "Cmts.User" user "User.Comments")
		(21 "Eco1.User" user "User.Eco1")
		(23 "Eco2.User" user "User.Eco2")
		(25 "Edge.Cuts" user "Board Geometry/Outline")
		(27 "Margin" user)
		(31 "F.CrtYd" user "Package Geometry/Place Bound Top")
		(29 "B.CrtYd" user "Package Geometry/Place Bound Bottom")
		(35 "F.Fab" user "Ref Des/Assembly Top")
		(33 "B.Fab" user "Ref Des/Assembly Bottom")
	)
	(footprint ""
		(layer "F.Cu")
		(at 327.533 -210.185)
		(property "Reference" "R4159"
			(at 0 0 0)
			(layer "F.SilkS")
			(hide yes)
			(effects
				(font
					(size 1.27 1.27)
				)
			)
		)
		(property "Value" ""
			(at 0 0 0)
			(layer "F.Fab")
			(effects
				(font
					(size 1.27 1.27)
				)
			)
		)
		(duplicate_pad_numbers_are_jumpers no)
		(fp_line
			(start -0.7874 -0.4064)
			(end 0.7874 -0.4064)
			(stroke
				(width 0.1524)
				(type default)
			)
			(layer "F.SilkS")
		)
		(fp_line
			(start -0.7874 0.4064)
			(end -0.7874 -0.4064)
			(stroke
				(width 0.1524)
				(type default)
			)
			(layer "F.SilkS")
		)
		(fp_line
			(start 0.7874 -0.4064)
			(end 0.7874 0.4064)
			(stroke
				(width 0.1524)
				(type default)
			)
			(layer "F.SilkS")
		)
		(fp_line
			(start 0.7874 0.4064)
			(end -0.7874 0.4064)
			(stroke
				(width 0.1524)
				(type default)
			)
			(layer "F.SilkS")
		)
		(fp_line
			(start -0.67945 -0.305054)
			(end -0.12065 -0.305054)
			(stroke
				(width 0.1)
				(type default)
			)
			(layer "F.Fab")
		)
		(fp_line
			(start -0.67945 0.3048)
			(end -0.67945 -0.305054)
			(stroke
				(width 0.1)
				(type default)
			)
			(layer "F.Fab")
		)
		(fp_line
			(start -0.12065 -0.305054)
			(end -0.12065 -0.2794)
			(stroke
				(width 0.1)
				(type default)
			)
			(layer "F.Fab")
		)
		(fp_line
			(start -0.12065 -0.2794)
			(end 0.12065 -0.2794)
			(stroke
				(width 0.1)
				(type default)
			)
			(layer "F.Fab")
		)
		(fp_line
			(start -0.12065 0.2794)
			(end -0.12065 0.3048)
			(stroke
				(width 0.1)
				(type default)
			)
			(layer "F.Fab")
		)
		(fp_line
			(start -0.12065 0.3048)
			(end -0.67945 0.3048)
			(stroke
				(width 0.1)
				(type default)
			)
			(layer "F.Fab")
		)
		(fp_line
			(start 0.120396 0.2794)
			(end -0.12065 0.2794)
			(stroke
				(width 0.1)
				(type default)
			)
			(layer "F.Fab")
		)
		(fp_line
			(start 0.120396 0.3048)
			(end 0.120396 0.2794)
			(stroke
				(width 0.1)
				(type default)
			)
			(layer "F.Fab")
		)
		(fp_line
			(start 0.12065 -0.3048)
			(end 0.67945 -0.3048)
			(stroke
				(width 0.1)
				(type default)
			)
			(layer "F.Fab")
		)
		(fp_line
			(start 0.12065 -0.2794)
			(end 0.12065 -0.3048)
			(stroke
				(width 0.1)
				(type default)
			)
			(layer "F.Fab")
		)
		(fp_line
			(start 0.67945 -0.3048)
			(end 0.67945 0.3048)
			(stroke
				(width 0.1)
				(type default)
			)
			(layer "F.Fab")
		)
		(fp_line
			(start 0.67945 0.3048)
			(end 0.120396 0.3048)
			(stroke
				(width 0.1)
				(type default)
			)
			(layer "F.Fab")
		)
		(pad "1" smd circle
			(at -0.40005 0)
			(size 0 0)
			(layers "F.Cu" "F.Mask" "F.Paste")
			(net "PRSNT_SSD12_FPGA_R_N")
		)
		(pad "2" smd circle
			(at 0.40005 0)
			(size 0 0)
			(layers "F.Cu" "F.Mask" "F.Paste")
			(net "PRSNT_SSD12_FPGA_N")
		)
	)
	(footprint ""
		(layer "F.Cu")
		(at 336.042 -181.991)
		(property "Reference" "R4724"
			(at 0 0 0)
			(layer "F.SilkS")
			(hide yes)
			(effects
				(font
					(size 1.27 1.27)
				)
			)
		)
		(property "Value" ""
			(at 0 0 0)
			(layer "F.Fab")
			(effects
				(font
					(size 1.27 1.27)
				)
			)
		)
		(duplicate_pad_numbers_are_jumpers no)
		(fp_line
			(start -0.7874 -0.4064)
			(end 0.7874 -0.4064)
			(stroke
				(width 0.1524)
				(type default)
			)
			(layer "F.SilkS")
		)
		(fp_line
			(start -0.7874 0.4064)
			(end -0.7874 -0.4064)
			(stroke
				(width 0.1524)
				(type default)
			)
			(layer "F.SilkS")
		)
		(fp_line
			(start 0.7874 -0.4064)
			(end 0.7874 0.4064)
			(stroke
				(width 0.1524)
				(type default)
			)
			(layer "F.SilkS")
		)
		(fp_line
			(start 0.7874 0.4064)
			(end -0.7874 0.4064)
			(stroke
				(width 0.1524)
				(type default)
			)
			(layer "F.SilkS")
		)
		(fp_line
			(start -0.67945 -0.305054)
			(end -0.12065 -0.305054)
			(stroke
				(width 0.1)
				(type default)
			)
			(layer "F.Fab")
		)
		(fp_line
			(start -0.67945 0.3048)
			(end -0.67945 -0.305054)
			(stroke
				(width 0.1)
				(type default)
			)
			(layer "F.Fab")
		)
		(fp_line
			(start -0.12065 -0.305054)
			(end -0.12065 -0.2794)
			(stroke
				(width 0.1)
				(type default)
			)
			(layer "F.Fab")
		)
		(fp_line
			(start -0.12065 -0.2794)
			(end 0.12065 -0.2794)
			(stroke
				(width 0.1)
				(type default)
			)
			(layer "F.Fab")
		)
		(fp_line
			(start -0.12065 0.2794)
			(end -0.12065 0.3048)
			(stroke
				(width 0.1)
				(type default)
			)
			(layer "F.Fab")
		)
		(fp_line
			(start -0.12065 0.3048)
			(end -0.67945 0.3048)
			(stroke
				(width 0.1)
				(type default)
			)
			(layer "F.Fab")
		)
		(fp_line
			(start 0.120396 0.2794)
			(end -0.12065 0.2794)
			(stroke
				(width 0.1)
				(type default)
			)
			(layer "F.Fab")
		)
		(fp_line
			(start 0.120396 0.3048)
			(end 0.120396 0.2794)
			(stroke
				(width 0.1)
				(type default)
			)
			(layer "F.Fab")
		)
		(fp_line
			(start 0.12065 -0.3048)
			(end 0.67945 -0.3048)
			(stroke
				(width 0.1)
				(type default)
			)
			(layer "F.Fab")
		)
		(fp_line
			(start 0.12065 -0.2794)
			(end 0.12065 -0.3048)
			(stroke
				(width 0.1)
				(type default)
			)
			(layer "F.Fab")
		)
		(fp_line
			(start 0.67945 -0.3048)
			(end 0.67945 0.3048)
			(stroke
				(width 0.1)
				(type default)
			)
			(layer "F.Fab")
		)
		(fp_line
			(start 0.67945 0.3048)
			(end 0.120396 0.3048)
			(stroke
				(width 0.1)
				(type default)
			)
			(layer "F.Fab")
		)
		(pad "1" smd circle
			(at -0.40005 0)
			(size 0 0)
			(layers "F.Cu" "F.Mask" "F.Paste")
			(net "P3V3_AUX")
		)
		(pad "2" smd circle
			(at 0.40005 0)
			(size 0 0)
			(layers "F.Cu" "F.Mask" "F.Paste")
			(net "SSD8_PEX_PWR_EN_R")
		)
	)
	(footprint ""
		(layer "F.Cu")
		(at 244.8433 -185.429652 -90)
		(property "Reference" "R3153"
			(at 0 0 270)
			(layer "F.SilkS")
			(hide yes)
			(effects
				(font
					(size 1.27 1.27)
				)
			)
		)
		(property "Value" ""
			(at 0 0 270)
			(layer "F.Fab")
			(effects
				(font
					(size 1.27 1.27)
				)
			)
		)
		(duplicate_pad_numbers_are_jumpers no)
		(fp_line
			(start -0.7874 0.4064)
			(end -0.7874 -0.4064)
			(stroke
				(width 0.1524)
				(type default)
			)
			(layer "F.SilkS")
		)
		(fp_line
			(start 0.7874 0.4064)
			(end -0.7874 0.4064)
			(stroke
				(width 0.1524)
				(type default)
			)
			(layer "F.SilkS")
		)
		(fp_line
			(start -0.7874 -0.4064)
			(end 0.7874 -0.4064)
			(stroke
				(width 0.1524)
				(type default)
			)
			(layer "F.SilkS")
		)
		(fp_line
			(start 0.7874 -0.4064)
			(end 0.7874 0.4064)
			(stroke
				(width 0.1524)
				(type default)
			)
			(layer "F.SilkS")
		)
		(fp_line
			(start -0.67945 0.3048)
			(end -0.67945 -0.305054)
			(stroke
				(width 0.1)
				(type default)
			)
			(layer "F.Fab")
		)
		(fp_line
			(start -0.12065 0.3048)
			(end -0.67945 0.3048)
			(stroke
				(width 0.1)
				(type default)
			)
			(layer "F.Fab")
		)
		(fp_line
			(start 0.120396 0.3048)
			(end 0.120396 0.2794)
			(stroke
				(width 0.1)
				(type default)
			)
			(layer "F.Fab")
		)
		(fp_line
			(start 0.67945 0.3048)
			(end 0.120396 0.3048)
			(stroke
				(width 0.1)
				(type default)
			)
			(layer "F.Fab")
		)
		(fp_line
			(start -0.12065 0.2794)
			(end -0.12065 0.3048)
			(stroke
				(width 0.1)
				(type default)
			)
			(layer "F.Fab")
		)
		(fp_line
			(start 0.120396 0.2794)
			(end -0.12065 0.2794)
			(stroke
				(width 0.1)
				(type default)
			)
			(layer "F.Fab")
		)
		(fp_line
			(start -0.12065 -0.2794)
			(end 0.12065 -0.2794)
			(stroke
				(width 0.1)
				(type default)
			)
			(layer "F.Fab")
		)
		(fp_line
			(start 0.12065 -0.2794)
			(end 0.12065 -0.3048)
			(stroke
				(width 0.1)
				(type default)
			)
			(layer "F.Fab")
		)
		(fp_line
			(start 0.12065 -0.3048)
			(end 0.67945 -0.3048)
			(stroke
				(width 0.1)
				(type default)
			)
			(layer "F.Fab")
		)
		(fp_line
			(start 0.67945 -0.3048)
			(end 0.67945 0.3048)
			(stroke
				(width 0.1)
				(type default)
			)
			(layer "F.Fab")
		)
		(fp_line
			(start -0.67945 -0.305054)
			(end -0.12065 -0.305054)
			(stroke
				(width 0.1)
				(type default)
			)
			(layer "F.Fab")
		)
		(fp_line
			(start -0.12065 -0.305054)
			(end -0.12065 -0.2794)
			(stroke
				(width 0.1)
				(type default)
			)
			(layer "F.Fab")
		)
		(pad "1" smd circle
			(at -0.40005 0 270)
			(size 0 0)
			(layers "F.Cu" "F.Mask" "F.Paste")
			(net "PWRGD_P1V2_AUX_DLY")
		)
		(pad "2" smd circle
			(at 0.40005 0 270)
			(size 0 0)
			(layers "F.Cu" "F.Mask" "F.Paste")
			(net "PWRGD_P1V2_AUX_RST")
		)
	)
	(footprint ""
		(layer "F.Cu")
		(at 258.44373 -43.85691)
		(property "Reference" "R597"
			(at 0 0 0)
			(layer "F.SilkS")
			(hide yes)
			(effects
				(font
					(size 1.27 1.27)
				)
			)
		)
		(property "Value" ""
			(at 0 0 0)
			(layer "F.Fab")
			(effects
				(font
					(size 1.27 1.27)
				)
			)
		)
		(duplicate_pad_numbers_are_jumpers no)
		(fp_line
			(start -0.7874 -0.4064)
			(end 0.7874 -0.4064)
			(stroke
				(width 0.1524)
				(type default)
			)
			(layer "F.SilkS")
		)
		(fp_line
			(start -0.7874 0.4064)
			(end -0.7874 -0.4064)
			(stroke
				(width 0.1524)
				(type default)
			)
			(layer "F.SilkS")
		)
		(fp_line
			(start 0.7874 -0.4064)
			(end 0.7874 0.4064)
			(stroke
				(width 0.1524)
				(type default)
			)
			(layer "F.SilkS")
		)
		(fp_line
			(start 0.7874 0.4064)
			(end -0.7874 0.4064)
			(stroke
				(width 0.1524)
				(type default)
			)
			(layer "F.SilkS")
		)
		(fp_line
			(start -0.67945 -0.305054)
			(end -0.12065 -0.305054)
			(stroke
				(width 0.1)
				(type default)
			)
			(layer "F.Fab")
		)
		(fp_line
			(start -0.67945 0.3048)
			(end -0.67945 -0.305054)
			(stroke
				(width 0.1)
				(type default)
			)
			(layer "F.Fab")
		)
		(fp_line
			(start -0.12065 -0.305054)
			(end -0.12065 -0.2794)
			(stroke
				(width 0.1)
				(type default)
			)
			(layer "F.Fab")
		)
		(fp_line
			(start -0.12065 -0.2794)
			(end 0.12065 -0.2794)
			(stroke
				(width 0.1)
				(type default)
			)
			(layer "F.Fab")
		)
		(fp_line
			(start -0.12065 0.2794)
			(end -0.12065 0.3048)
			(stroke
				(width 0.1)
				(type default)
			)
			(layer "F.Fab")
		)
		(fp_line
			(start -0.12065 0.3048)
			(end -0.67945 0.3048)
			(stroke
				(width 0.1)
				(type default)
			)
			(layer "F.Fab")
		)
		(fp_line
			(start 0.120396 0.2794)
			(end -0.12065 0.2794)
			(stroke
				(width 0.1)
				(type default)
			)
			(layer "F.Fab")
		)
		(fp_line
			(start 0.120396 0.3048)
			(end 0.120396 0.2794)
			(stroke
				(width 0.1)
				(type default)
			)
			(layer "F.Fab")
		)
		(fp_line
			(start 0.12065 -0.3048)
			(end 0.67945 -0.3048)
			(stroke
				(width 0.1)
				(type default)
			)
			(layer "F.Fab")
		)
		(fp_line
			(start 0.12065 -0.2794)
			(end 0.12065 -0.3048)
			(stroke
				(width 0.1)
				(type default)
			)
			(layer "F.Fab")
		)
		(fp_line
			(start 0.67945 -0.3048)
			(end 0.67945 0.3048)
			(stroke
				(width 0.1)
				(type default)
			)
			(layer "F.Fab")
		)
		(fp_line
			(start 0.67945 0.3048)
			(end 0.120396 0.3048)
			(stroke
				(width 0.1)
				(type default)
			)
			(layer "F.Fab")
		)
		(pad "1" smd circle
			(at -0.40005 0)
			(size 0 0)
			(layers "F.Cu" "F.Mask" "F.Paste")
			(net "SSD8_ADC_A1")
		)
		(pad "2" smd circle
			(at 0.40005 0)
			(size 0 0)
			(layers "F.Cu" "F.Mask" "F.Paste")
			(net "GND")
		)
	)
	(footprint ""
		(layer "F.Cu")
		(at 386.90804 -155.3464 180)
		(property "Reference" "R320"
			(at 0 0 180)
			(layer "F.SilkS")
			(hide yes)
			(effects
				(font
					(size 1.27 1.27)
				)
			)
		)
		(property "Value" ""
			(at 0 0 180)
			(layer "F.Fab")
			(effects
				(font
					(size 1.27 1.27)
				)
			)
		)
		(duplicate_pad_numbers_are_jumpers no)
		(fp_line
			(start 0.7874 0.4064)
			(end -0.7874 0.4064)
			(stroke
				(width 0.1524)
				(type default)
			)
			(layer "F.SilkS")
		)
		(fp_line
			(start 0.7874 -0.4064)
			(end 0.7874 0.4064)
			(stroke
				(width 0.1524)
				(type default)
			)
			(layer "F.SilkS")
		)
		(fp_line
			(start -0.7874 0.4064)
			(end -0.7874 -0.4064)
			(stroke
				(width 0.1524)
				(type default)
			)
			(layer "F.SilkS")
		)
		(fp_line
			(start -0.7874 -0.4064)
			(end 0.7874 -0.4064)
			(stroke
				(width 0.1524)
				(type default)
			)
			(layer "F.SilkS")
		)
		(fp_line
			(start 0.67945 0.3048)
			(end 0.120396 0.3048)
			(stroke
				(width 0.1)
				(type default)
			)
			(layer "F.Fab")
		)
		(fp_line
			(start 0.67945 -0.3048)
			(end 0.67945 0.3048)
			(stroke
				(width 0.1)
				(type default)
			)
			(layer "F.Fab")
		)
		(fp_line
			(start 0.12065 -0.2794)
			(end 0.12065 -0.3048)
			(stroke
				(width 0.1)
				(type default)
			)
			(layer "F.Fab")
		)
		(fp_line
			(start 0.12065 -0.3048)
			(end 0.67945 -0.3048)
			(stroke
				(width 0.1)
				(type default)
			)
			(layer "F.Fab")
		)
		(fp_line
			(start 0.120396 0.3048)
			(end 0.120396 0.2794)
			(stroke
				(width 0.1)
				(type default)
			)
			(layer "F.Fab")
		)
		(fp_line
			(start 0.120396 0.2794)
			(end -0.12065 0.2794)
			(stroke
				(width 0.1)
				(type default)
			)
			(layer "F.Fab")
		)
		(fp_line
			(start -0.12065 0.3048)
			(end -0.67945 0.3048)
			(stroke
				(width 0.1)
				(type default)
			)
			(layer "F.Fab")
		)
		(fp_line
			(start -0.12065 0.2794)
			(end -0.12065 0.3048)
			(stroke
				(width 0.1)
				(type default)
			)
			(layer "F.Fab")
		)
		(fp_line
			(start -0.12065 -0.2794)
			(end 0.12065 -0.2794)
			(stroke
				(width 0.1)
				(type default)
			)
			(layer "F.Fab")
		)
		(fp_line
			(start -0.12065 -0.305054)
			(end -0.12065 -0.2794)
			(stroke
				(width 0.1)
				(type default)
			)
			(layer "F.Fab")
		)
		(fp_line
			(start -0.67945 0.3048)
			(end -0.67945 -0.305054)
			(stroke
				(width 0.1)
				(type default)
			)
			(layer "F.Fab")
		)
		(fp_line
			(start -0.67945 -0.305054)
			(end -0.12065 -0.305054)
			(stroke
				(width 0.1)
				(type default)
			)
			(layer "F.Fab")
		)
		(pad "1" smd circle
			(at -0.40005 0 180)
			(size 0 0)
			(layers "F.Cu" "F.Mask" "F.Paste")
			(net "NIC6_CLK")
		)
		(pad "2" smd circle
			(at 0.40005 0 180)
			(size 0 0)
			(layers "F.Cu" "F.Mask" "F.Paste")
			(net "GND")
		)
	)
	(footprint ""
		(layer "F.Cu")
		(at 13.0175 -310.384952)
		(property "Reference" "PC209"
			(at 0 0 0)
			(layer "F.SilkS")
			(hide yes)
			(effects
				(font
					(size 1.27 1.27)
				)
			)
		)
		(property "Value" ""
			(at 0 0 0)
			(layer "F.Fab")
			(effects
				(font
					(size 1.27 1.27)
				)
			)
		)
		(duplicate_pad_numbers_are_jumpers no)
		(fp_line
			(start -1.524 -0.762)
			(end 1.524 -0.762)
			(stroke
				(width 0.1524)
				(type default)
			)
			(layer "F.SilkS")
		)
		(fp_line
			(start -1.524 0.762)
			(end -1.524 -0.762)
			(stroke
				(width 0.1524)
				(type default)
			)
			(layer "F.SilkS")
		)
		(fp_line
			(start 1.524 -0.762)
			(end 1.524 0.762)
			(stroke
				(width 0.1524)
				(type default)
			)
			(layer "F.SilkS")
		)
		(fp_line
			(start 1.524 0.762)
			(end -1.524 0.762)
			(stroke
				(width 0.1524)
				(type default)
			)
			(layer "F.SilkS")
		)
		(fp_line
			(start -1.1049 -0.724916)
			(end -1.1049 0.724916)
			(stroke
				(width 0.1)
				(type default)
			)
			(layer "F.Fab")
		)
		(fp_line
			(start -1.1049 0.724916)
			(end 1.1049 0.724916)
			(stroke
				(width 0.1)
				(type default)
			)
			(layer "F.Fab")
		)
		(fp_line
			(start 1.1049 -0.724916)
			(end -1.1049 -0.724916)
			(stroke
				(width 0.1)
				(type default)
			)
			(layer "F.Fab")
		)
		(fp_line
			(start 1.1049 0.724916)
			(end 1.1049 -0.724916)
			(stroke
				(width 0.1)
				(type default)
			)
			(layer "F.Fab")
		)
		(pad "1" smd rect
			(at -0.889 0 180)
			(size 1.016 1.27)
			(layers "F.Cu" "F.Mask" "F.Paste")
			(net "SW_P12V_P1V25_PEX0_FLT")
		)
		(pad "2" smd rect
			(at 0.889 0 180)
			(size 1.016 1.27)
			(layers "F.Cu" "F.Mask" "F.Paste")
			(net "GND")
		)
	)
)
